# S9S_MB_2U (Grand Teton) — schematic netlist excerpt (pin names and nets, part order shuffled) for the footprints in the layout excerpt that follows; sources: Cadence DE-HDL packaged netlist, KiCad conversion of 03242023_DA0F0TMBIJ0_F0T_Motherboard_J_brd_V01_OCP.brd

R2572  Q_RES  0 5% CHIP  pkg 0402LF  page 292 : A = PWRGD_PVCCFA_EHV_CPU1 ; B = PWRGD_PVCCFA_EHV_CPU1_R
R304  Q_RES  0 5% CHIP  pkg 0402LF  page 118 : A = H_CPU1_RMCA_LVC1_R_N ; B = H_CPU_RMCA_LVC1_R_N

(kicad_pcb
	(version 20260206)
	(generator "pcbnew")
	(generator_version "10.0")
	(general
		(thickness 1.6)
		(legacy_teardrops no)
	)
	(paper "A4")
	(title_block
		(title "03242023_DA0F0TMBIJ0_F0T_Motherboard_J_brd_V01_OCP.brd")
		(comment 1 "Grand Teton / footprints 5823-5824 of 6105")
	)
	(layers
		(0 "F.Cu" signal "TOP")
		(4 "In1.Cu" signal "GND")
		(6 "In2.Cu" signal "IN1")
		(8 "In3.Cu" signal "GND1")
		(10 "In4.Cu" signal "IN2")
		(12 "In5.Cu" signal "GND2")
		(14 "In6.Cu" signal "IN3")
		(16 "In7.Cu" signal "GND3")
		(18 "In8.Cu" signal "VCC")
		(20 "In9.Cu" signal "VCC1")
		(22 "In10.Cu" signal "GND4")
		(24 "In11.Cu" signal "IN4")
		(26 "In12.Cu" signal "GND5")
		(28 "In13.Cu" signal "IN5")
		(30 "In14.Cu" signal "GND6")
		(32 "In15.Cu" signal "IN6")
		(34 "In16.Cu" signal "GND7")
		(2 "B.Cu" signal "BOTTOM")
		(9 "F.Adhes" user "F.Adhesive")
		(11 "B.Adhes" user "B.Adhesive")
		(13 "F.Paste" user "Package Geometry/Pastemask Top")
		(15 "B.Paste" user "Package Geometry/Pastemask Bottom")
		(5 "F.SilkS" user "Ref Des/Silkscreen Top")
		(7 "B.SilkS" user "Ref Des/Silkscreen Bottom")
		(1 "F.Mask" user "Board Geometry/Soldermask Top")
		(3 "B.Mask" user "Board Geometry/Soldermask Bottom")
		(17 "Dwgs.User" user "User.Drawings")
		(19 "Cmts.User" user "User.Comments")
		(21 "Eco1.User" user "User.Eco1")
		(23 "Eco2.User" user "User.Eco2")
		(25 "Edge.Cuts" user "Board Geometry/Outline")
		(27 "Margin" user)
		(31 "F.CrtYd" user "Package Geometry/Place Bound Top")
		(29 "B.CrtYd" user "Package Geometry/Place Bound Bottom")
		(35 "F.Fab" user "Ref Des/Assembly Top")
		(33 "B.Fab" user "Ref Des/Assembly Bottom")
	)
	(footprint ""
		(layer "B.Cu")
		(at 36.956238 -131.77774)
		(property "Reference" "R2572"
			(at 0 0 0)
			(layer "B.SilkS")
			(hide yes)
			(effects
				(font
					(size 1.27 1.27)
				)
				(justify mirror)
			)
		)
		(property "Value" ""
			(at 0 0 0)
			(layer "B.Fab")
			(effects
				(font
					(size 1.27 1.27)
				)
				(justify mirror)
			)
		)
		(duplicate_pad_numbers_are_jumpers no)
		(fp_line
			(start -0.7874 -0.4064)
			(end -0.7874 0.4064)
			(stroke
				(width 0.1524)
				(type default)
			)
			(layer "B.SilkS")
		)
		(fp_line
			(start -0.7874 0.4064)
			(end 0.7874 0.4064)
			(stroke
				(width 0.1524)
				(type default)
			)
			(layer "B.SilkS")
		)
		(fp_line
			(start 0.7874 -0.4064)
			(end -0.7874 -0.4064)
			(stroke
				(width 0.1524)
				(type default)
			)
			(layer "B.SilkS")
		)
		(fp_line
			(start 0.7874 0.4064)
			(end 0.7874 -0.4064)
			(stroke
				(width 0.1524)
				(type default)
			)
			(layer "B.SilkS")
		)
		(fp_line
			(start -0.67945 -0.3048)
			(end -0.67945 0.3048)
			(stroke
				(width 0.1)
				(type default)
			)
			(layer "B.Fab")
		)
		(fp_line
			(start -0.67945 0.3048)
			(end -0.120396 0.3048)
			(stroke
				(width 0.1)
				(type default)
			)
			(layer "B.Fab")
		)
		(fp_line
			(start -0.12065 -0.3048)
			(end -0.67945 -0.3048)
			(stroke
				(width 0.1)
				(type default)
			)
			(layer "B.Fab")
		)
		(fp_line
			(start -0.12065 -0.2794)
			(end -0.12065 -0.3048)
			(stroke
				(width 0.1)
				(type default)
			)
			(layer "B.Fab")
		)
		(fp_line
			(start -0.120396 0.2794)
			(end 0.12065 0.2794)
			(stroke
				(width 0.1)
				(type default)
			)
			(layer "B.Fab")
		)
		(fp_line
			(start -0.120396 0.3048)
			(end -0.120396 0.2794)
			(stroke
				(width 0.1)
				(type default)
			)
			(layer "B.Fab")
		)
		(fp_line
			(start 0.12065 -0.305054)
			(end 0.12065 -0.2794)
			(stroke
				(width 0.1)
				(type default)
			)
			(layer "B.Fab")
		)
		(fp_line
			(start 0.12065 -0.2794)
			(end -0.12065 -0.2794)
			(stroke
				(width 0.1)
				(type default)
			)
			(layer "B.Fab")
		)
		(fp_line
			(start 0.12065 0.2794)
			(end 0.12065 0.3048)
			(stroke
				(width 0.1)
				(type default)
			)
			(layer "B.Fab")
		)
		(fp_line
			(start 0.12065 0.3048)
			(end 0.67945 0.3048)
			(stroke
				(width 0.1)
				(type default)
			)
			(layer "B.Fab")
		)
		(fp_line
			(start 0.67945 -0.305054)
			(end 0.12065 -0.305054)
			(stroke
				(width 0.1)
				(type default)
			)
			(layer "B.Fab")
		)
		(fp_line
			(start 0.67945 0.3048)
			(end 0.67945 -0.305054)
			(stroke
				(width 0.1)
				(type default)
			)
			(layer "B.Fab")
		)
		(pad "1" smd circle
			(at 0.40005 0 180)
			(size 0 0)
			(layers "B.Cu" "B.Mask" "B.Paste")
			(net "PWRGD_PVCCFA_EHV_CPU1")
		)
		(pad "2" smd circle
			(at -0.40005 0 180)
			(size 0 0)
			(layers "B.Cu" "B.Mask" "B.Paste")
			(net "PWRGD_PVCCFA_EHV_CPU1_R")
		)
	)
	(footprint ""
		(layer "B.Cu")
		(at 84.974684 -188.035692 90)
		(property "Reference" "R304"
			(at 0 0 90)
			(layer "B.SilkS")
			(hide yes)
			(effects
				(font
					(size 1.27 1.27)
				)
				(justify mirror)
			)
		)
		(property "Value" ""
			(at 0 0 90)
			(layer "B.Fab")
			(effects
				(font
					(size 1.27 1.27)
				)
				(justify mirror)
			)
		)
		(duplicate_pad_numbers_are_jumpers no)
		(fp_line
			(start 0.7874 -0.4064)
			(end -0.7874 -0.4064)
			(stroke
				(width 0.1524)
				(type default)
			)
			(layer "B.SilkS")
		)
		(fp_line
			(start -0.7874 -0.4064)
			(end -0.7874 0.4064)
			(stroke
				(width 0.1524)
				(type default)
			)
			(layer "B.SilkS")
		)
		(fp_line
			(start 0.7874 0.4064)
			(end 0.7874 -0.4064)
			(stroke
				(width 0.1524)
				(type default)
			)
			(layer "B.SilkS")
		)
		(fp_line
			(start -0.7874 0.4064)
			(end 0.7874 0.4064)
			(stroke
				(width 0.1524)
				(type default)
			)
			(layer "B.SilkS")
		)
		(fp_line
			(start 0.67945 -0.305054)
			(end 0.12065 -0.305054)
			(stroke
				(width 0.1)
				(type default)
			)
			(layer "B.Fab")
		)
		(fp_line
			(start 0.12065 -0.305054)
			(end 0.12065 -0.2794)
			(stroke
				(width 0.1)
				(type default)
			)
			(layer "B.Fab")
		)
		(fp_line
			(start -0.12065 -0.3048)
			(end -0.67945 -0.3048)
			(stroke
				(width 0.1)
				(type default)
			)
			(layer "B.Fab")
		)
		(fp_line
			(start -0.67945 -0.3048)
			(end -0.67945 0.3048)
			(stroke
				(width 0.1)
				(type default)
			)
			(layer "B.Fab")
		)
		(fp_line
			(start 0.12065 -0.2794)
			(end -0.12065 -0.2794)
			(stroke
				(width 0.1)
				(type default)
			)
			(layer "B.Fab")
		)
		(fp_line
			(start -0.12065 -0.2794)
			(end -0.12065 -0.3048)
			(stroke
				(width 0.1)
				(type default)
			)
			(layer "B.Fab")
		)
		(fp_line
			(start 0.12065 0.2794)
			(end 0.12065 0.3048)
			(stroke
				(width 0.1)
				(type default)
			)
			(layer "B.Fab")
		)
		(fp_line
			(start -0.120396 0.2794)
			(end 0.12065 0.2794)
			(stroke
				(width 0.1)
				(type default)
			)
			(layer "B.Fab")
		)
		(fp_line
			(start 0.67945 0.3048)
			(end 0.67945 -0.305054)
			(stroke
				(width 0.1)
				(type default)
			)
			(layer "B.Fab")
		)
		(fp_line
			(start 0.12065 0.3048)
			(end 0.67945 0.3048)
			(stroke
				(width 0.1)
				(type default)
			)
			(layer "B.Fab")
		)
		(fp_line
			(start -0.120396 0.3048)
			(end -0.120396 0.2794)
			(stroke
				(width 0.1)
				(type default)
			)
			(layer "B.Fab")
		)
		(fp_line
			(start -0.67945 0.3048)
			(end -0.120396 0.3048)
			(stroke
				(width 0.1)
				(type default)
			)
			(layer "B.Fab")
		)
		(pad "1" smd circle
			(at 0.40005 0 270)
			(size 0 0)
			(layers "B.Cu" "B.Mask" "B.Paste")
			(net "H_CPU1_RMCA_LVC1_R_N")
		)
		(pad "2" smd circle
			(at -0.40005 0 270)
			(size 0 0)
			(layers "B.Cu" "B.Mask" "B.Paste")
			(net "H_CPU_RMCA_LVC1_R_N")
		)
	)
)
